# T6G (Grand Teton) — schematic netlist excerpt (pin names and nets, part order shuffled) for the footprints in the layout excerpt that follows; sources: Cadence DE-HDL packaged netlist, KiCad conversion of 04192023_DAF0TMB3IC0_F0TG_MB_C_brd_V02_OCP.brd

C253  Q_CAP  0.1UF 10V 10% X7S  pkg C0201  page 323 : A = P0V9_CPU1_RT0_2A ; B = GND

Q84  MOSFET_NCH_DUAL  PJT138K IC  pkg SOT363XD  page 256
  S1  = GND
  G1  = FM_LED_PWRGD_PVDDCR_CPU0_P1
  D2  = LED_PWRGD_PVDDCR_SOC_P1_D
  S2  = GND
  G2  = FM_LED_PWRGD_PVDDCR_SOC_P1
  D1  = LED_PWRGD_PVDDCR_CPU0_P1_D

R1115  Q_RES  4.7K 5% CHIP  pkg 0201LF  page 309 : A = TEST0_RT_CPU0_P3 ; B = GND

(kicad_pcb
	(version 20260206)
	(generator "pcbnew")
	(generator_version "10.0")
	(general
		(thickness 1.6)
		(legacy_teardrops no)
	)
	(paper "A4")
	(title_block
		(title "04192023_DAF0TMB3IC0_F0TG_MB_C_brd_V02_OCP.brd")
		(comment 1 "Grand Teton / footprints 8185-8187 of 8354")
	)
	(layers
		(0 "F.Cu" signal "TOP")
		(4 "In1.Cu" signal "GND")
		(6 "In2.Cu" signal "IN1")
		(8 "In3.Cu" signal "GND1")
		(10 "In4.Cu" signal "IN2")
		(12 "In5.Cu" signal "GND2")
		(14 "In6.Cu" signal "IN3")
		(16 "In7.Cu" signal "GND3")
		(18 "In8.Cu" signal "VCC")
		(20 "In9.Cu" signal "VCC1")
		(22 "In10.Cu" signal "GND4")
		(24 "In11.Cu" signal "IN4")
		(26 "In12.Cu" signal "GND5")
		(28 "In13.Cu" signal "IN5")
		(30 "In14.Cu" signal "GND6")
		(32 "In15.Cu" signal "IN6")
		(34 "In16.Cu" signal "GND7")
		(2 "B.Cu" signal "BOTTOM")
		(9 "F.Adhes" user "F.Adhesive")
		(11 "B.Adhes" user "B.Adhesive")
		(13 "F.Paste" user "Package Geometry/Pastemask Top")
		(15 "B.Paste" user "Package Geometry/Pastemask Bottom")
		(5 "F.SilkS" user "Ref Des/Silkscreen Top")
		(7 "B.SilkS" user "Ref Des/Silkscreen Bottom")
		(1 "F.Mask" user "Board Geometry/Soldermask Top")
		(3 "B.Mask" user "Board Geometry/Soldermask Bottom")
		(17 "Dwgs.User" user "User.Drawings")
		(19 "Cmts.User" user "User.Comments")
		(21 "Eco1.User" user "User.Eco1")
		(23 "Eco2.User" user "User.Eco2")
		(25 "Edge.Cuts" user "Board Geometry/Outline")
		(27 "Margin" user)
		(31 "F.CrtYd" user "Package Geometry/Place Bound Top")
		(29 "B.CrtYd" user "Package Geometry/Place Bound Bottom")
		(35 "F.Fab" user "Ref Des/Assembly Top")
		(33 "B.Fab" user "Ref Des/Assembly Bottom")
	)
	(footprint ""
		(layer "B.Cu")
		(at 65.518538 -388.011162 -90)
		(property "Reference" "C253"
			(at 0 0 90)
			(layer "B.SilkS")
			(hide yes)
			(effects
				(font
					(size 1.27 1.27)
				)
				(justify mirror)
			)
		)
		(property "Value" ""
			(at 0 0 90)
			(layer "B.Fab")
			(effects
				(font
					(size 1.27 1.27)
				)
				(justify mirror)
			)
		)
		(duplicate_pad_numbers_are_jumpers no)
		(fp_line
			(start -0.299974 0.150114)
			(end 0.299974 0.150114)
			(stroke
				(width 0.1)
				(type default)
			)
			(layer "B.Fab")
		)
		(fp_line
			(start 0.299974 0.150114)
			(end 0.299974 -0.150114)
			(stroke
				(width 0.1)
				(type default)
			)
			(layer "B.Fab")
		)
		(fp_line
			(start -0.299974 -0.150114)
			(end -0.299974 0.150114)
			(stroke
				(width 0.1)
				(type default)
			)
			(layer "B.Fab")
		)
		(fp_line
			(start 0.299974 -0.150114)
			(end -0.299974 -0.150114)
			(stroke
				(width 0.1)
				(type default)
			)
			(layer "B.Fab")
		)
		(pad "1" smd rect
			(at 0.2667 0 90)
			(size 0.3048 0.381)
			(layers "B.Cu" "B.Mask" "B.Paste")
			(net "P0V9_CPU1_RT0_2A")
		)
		(pad "2" smd rect
			(at -0.2667 0 90)
			(size 0.3048 0.381)
			(layers "B.Cu" "B.Mask" "B.Paste")
			(net "GND")
		)
	)
	(footprint ""
		(layer "B.Cu")
		(at 338.560664 -73.534778)
		(property "Reference" "Q84"
			(at 1.4224 -1.768348 0)
			(unlocked yes)
			(layer "B.SilkS")
			(effects
				(font
					(size 0.7874 0.5842)
					(thickness 0.1524)
				)
				(justify left mirror)
			)
		)
		(property "Value" ""
			(at 0 0 0)
			(layer "B.Fab")
			(effects
				(font
					(size 1.27 1.27)
				)
				(justify mirror)
			)
		)
		(duplicate_pad_numbers_are_jumpers no)
		(fp_line
			(start -1.332738 -1.100074)
			(end -1.332738 1.100074)
			(stroke
				(width 0.1524)
				(type default)
			)
			(layer "B.SilkS")
		)
		(fp_line
			(start -1.332738 1.100074)
			(end 1.332738 1.100074)
			(stroke
				(width 0.1524)
				(type default)
			)
			(layer "B.SilkS")
		)
		(fp_line
			(start -0.4826 -1.100074)
			(end -1.332738 -1.100074)
			(stroke
				(width 0.1524)
				(type default)
			)
			(layer "B.SilkS")
		)
		(fp_line
			(start 0 -0.541274)
			(end -0.4826 -1.100074)
			(stroke
				(width 0.1524)
				(type default)
			)
			(layer "B.SilkS")
		)
		(fp_line
			(start 0.4826 -1.100074)
			(end 0 -0.541274)
			(stroke
				(width 0.1524)
				(type default)
			)
			(layer "B.SilkS")
		)
		(fp_line
			(start 1.332738 -1.100074)
			(end 0.4826 -1.100074)
			(stroke
				(width 0.1524)
				(type default)
			)
			(layer "B.SilkS")
		)
		(fp_line
			(start 1.332738 1.100074)
			(end 1.332738 -1.100074)
			(stroke
				(width 0.1524)
				(type default)
			)
			(layer "B.SilkS")
		)
		(fp_poly
			(pts
				(xy 1.378458 -0.627888) (xy 2.080514 -0.978916) (xy 2.080514 -0.27686)
			)
			(stroke
				(width 0)
				(type default)
			)
			(fill yes)
			(layer "B.SilkS")
		)
		(fp_line
			(start -0.674878 -1.100074)
			(end -0.674878 1.100074)
			(stroke
				(width 0.1)
				(type default)
			)
			(layer "B.Fab")
		)
		(fp_line
			(start -0.674878 1.100074)
			(end 0.674878 1.100074)
			(stroke
				(width 0.1)
				(type default)
			)
			(layer "B.Fab")
		)
		(fp_line
			(start 0.674878 -1.100074)
			(end -0.674878 -1.100074)
			(stroke
				(width 0.1)
				(type default)
			)
			(layer "B.Fab")
		)
		(fp_line
			(start 0.674878 1.100074)
			(end 0.674878 -1.100074)
			(stroke
				(width 0.1)
				(type default)
			)
			(layer "B.Fab")
		)
		(fp_poly
			(pts
				(xy 2.2352 -0.298958) (xy 2.2352 -1.001014) (xy 1.533144 -0.649986)
			)
			(stroke
				(width 0)
				(type default)
			)
			(fill yes)
			(layer "B.Fab")
		)
		(pad "1" smd rect
			(at 0.94996 -0.649986 90)
			(size 0.4318 0.508)
			(layers "B.Cu" "B.Mask" "B.Paste")
			(net "GND")
		)
		(pad "2" smd rect
			(at 0.94996 0 90)
			(size 0.4318 0.508)
			(layers "B.Cu" "B.Mask" "B.Paste")
			(net "FM_LED_PWRGD_PVDDCR_CPU0_P1")
		)
		(pad "3" smd rect
			(at 0.94996 0.649986 90)
			(size 0.4318 0.508)
			(layers "B.Cu" "B.Mask" "B.Paste")
			(net "LED_PWRGD_PVDDCR_SOC_P1_D")
		)
		(pad "4" smd rect
			(at -0.94996 0.649986 90)
			(size 0.4318 0.508)
			(layers "B.Cu" "B.Mask" "B.Paste")
			(net "GND")
		)
		(pad "5" smd rect
			(at -0.94996 0 90)
			(size 0.4318 0.508)
			(layers "B.Cu" "B.Mask" "B.Paste")
			(net "FM_LED_PWRGD_PVDDCR_SOC_P1")
		)
		(pad "6" smd rect
			(at -0.94996 -0.649986 90)
			(size 0.4318 0.508)
			(layers "B.Cu" "B.Mask" "B.Paste")
			(net "LED_PWRGD_PVDDCR_CPU0_P1_D")
		)
	)
	(footprint ""
		(layer "B.Cu")
		(at 366.36579 -393.96416 180)
		(property "Reference" "R1115"
			(at 0 0 0)
			(layer "B.SilkS")
			(hide yes)
			(effects
				(font
					(size 1.27 1.27)
				)
				(justify mirror)
			)
		)
		(property "Value" ""
			(at 0 0 0)
			(layer "B.Fab")
			(effects
				(font
					(size 1.27 1.27)
				)
				(justify mirror)
			)
		)
		(duplicate_pad_numbers_are_jumpers no)
		(fp_line
			(start 0.32512 0.175006)
			(end 0.32512 -0.175006)
			(stroke
				(width 0.1)
				(type default)
			)
			(layer "B.Fab")
		)
		(fp_line
			(start 0.32512 -0.175006)
			(end -0.32512 -0.175006)
			(stroke
				(width 0.1)
				(type default)
			)
			(layer "B.Fab")
		)
		(fp_line
			(start -0.32512 0.175006)
			(end 0.32512 0.175006)
			(stroke
				(width 0.1)
				(type default)
			)
			(layer "B.Fab")
		)
		(fp_line
			(start -0.32512 -0.175006)
			(end -0.32512 0.175006)
			(stroke
				(width 0.1)
				(type default)
			)
			(layer "B.Fab")
		)
		(pad "1" smd rect
			(at 0.2667 0)
			(size 0.3048 0.381)
			(layers "B.Cu" "B.Mask" "B.Paste")
			(net "TEST0_RT_CPU0_P3")
		)
		(pad "2" smd rect
			(at -0.2667 0 180)
			(size 0.3048 0.381)
			(layers "B.Cu" "B.Mask" "B.Paste")
			(net "GND")
		)
	)
)
